# T6G (Grand Teton) — schematic netlist excerpt (pin names and nets, part order shuffled) for the footprints in the layout excerpt that follows; sources: Cadence DE-HDL packaged netlist, KiCad conversion of 04192023_DAF0TMB3IC0_F0TG_MB_C_brd_V02_OCP.brd

PU14  ISL99390FRZTR5935  ISL99390FRZ-TR5935 IC  pkg QFN21_6X5XB  page 202
  VOS  = PVDDCR_CPU1_P0_VOS4
  AGND  = GND
  VCC  = PVDDCR_CPU1_P0_VCC4
  PVCC  = PVDDCR_CPU1_P0_PVCC
  PGND1  = GND
  GL1  = NC_PVDDCR_CPU1_P0_GL1_4
  PGND2  = GND
  SW  = SW_PVDDCR_CPU1_P0_SW4
  VIN1  = SW_P12V_AUX_PVDDCR_CPU1_P0_FLT
  VIN2  = SW_P12V_AUX_PVDDCR_CPU1_P0_FLT
  DNC  = NC_PVDDCR_CPU1_P0_DNC4
  PHASE  = SW_PVDDCR_CPU1_P0_BOOTR4
  BOOT  = SW_PVDDCR_CPU1_P0_BOOT4
  PWM  = PVDDCR_CPU1_P0_PWM4
  EN  = PVDDCR_CPU1_P0_VCC4
  TOUT_FLT  = PVDDCR_CPU1_P0_TEMP0
  LSET  = PVDDCR_CPU1_P0_LSET4
  IOUT  = PVDDCR_CPU1_P0_IMON4
  REFIN  = PVDDCR_CPU1_P0_VCCS
  PGND3  = GND
  GL2  = NC_PVDDCR_CPU1_P0_GL2_4

(kicad_pcb
	(version 20260206)
	(generator "pcbnew")
	(generator_version "10.0")
	(general
		(thickness 1.6)
		(legacy_teardrops no)
	)
	(paper "A4")
	(title_block
		(title "04192023_DAF0TMB3IC0_F0TG_MB_C_brd_V02_OCP.brd")
		(comment 1 "Grand Teton / footprints 4649-4649 of 8354")
	)
	(layers
		(0 "F.Cu" signal "TOP")
		(4 "In1.Cu" signal "GND")
		(6 "In2.Cu" signal "IN1")
		(8 "In3.Cu" signal "GND1")
		(10 "In4.Cu" signal "IN2")
		(12 "In5.Cu" signal "GND2")
		(14 "In6.Cu" signal "IN3")
		(16 "In7.Cu" signal "GND3")
		(18 "In8.Cu" signal "VCC")
		(20 "In9.Cu" signal "VCC1")
		(22 "In10.Cu" signal "GND4")
		(24 "In11.Cu" signal "IN4")
		(26 "In12.Cu" signal "GND5")
		(28 "In13.Cu" signal "IN5")
		(30 "In14.Cu" signal "GND6")
		(32 "In15.Cu" signal "IN6")
		(34 "In16.Cu" signal "GND7")
		(2 "B.Cu" signal "BOTTOM")
		(9 "F.Adhes" user "F.Adhesive")
		(11 "B.Adhes" user "B.Adhesive")
		(13 "F.Paste" user "Package Geometry/Pastemask Top")
		(15 "B.Paste" user "Package Geometry/Pastemask Bottom")
		(5 "F.SilkS" user "Ref Des/Silkscreen Top")
		(7 "B.SilkS" user "Ref Des/Silkscreen Bottom")
		(1 "F.Mask" user "Board Geometry/Soldermask Top")
		(3 "B.Mask" user "Board Geometry/Soldermask Bottom")
		(17 "Dwgs.User" user "User.Drawings")
		(19 "Cmts.User" user "User.Comments")
		(21 "Eco1.User" user "User.Eco1")
		(23 "Eco2.User" user "User.Eco2")
		(25 "Edge.Cuts" user "Board Geometry/Outline")
		(27 "Margin" user)
		(31 "F.CrtYd" user "Package Geometry/Place Bound Top")
		(29 "B.CrtYd" user "Package Geometry/Place Bound Bottom")
		(35 "F.Fab" user "Ref Des/Assembly Top")
		(33 "B.Fab" user "Ref Des/Assembly Bottom")
	)
	(footprint ""
		(layer "F.Cu")
		(at 308.696106 -346.71635)
		(property "Reference" "PU14"
			(at -6.182106 -6.82498 0)
			(unlocked yes)
			(layer "F.SilkS")
			(effects
				(font
					(size 0.7874 0.5842)
					(thickness 0.1524)
				)
				(justify left)
			)
		)
		(property "Value" ""
			(at 0 0 0)
			(layer "F.Fab")
			(effects
				(font
					(size 1.27 1.27)
				)
			)
		)
		(duplicate_pad_numbers_are_jumpers no)
		(fp_line
			(start -2.500122 -2.999994)
			(end -2.24409 -2.999994)
			(stroke
				(width 0.1524)
				(type default)
			)
			(layer "F.SilkS")
		)
		(fp_line
			(start -2.500122 -2.529078)
			(end -2.500122 -2.999994)
			(stroke
				(width 0.1524)
				(type default)
			)
			(layer "F.SilkS")
		)
		(fp_line
			(start -2.500122 0.6604)
			(end -2.500122 0.229108)
			(stroke
				(width 0.1524)
				(type default)
			)
			(layer "F.SilkS")
		)
		(fp_line
			(start -2.500122 2.999994)
			(end -2.500122 2.339594)
			(stroke
				(width 0.1524)
				(type default)
			)
			(layer "F.SilkS")
		)
		(fp_line
			(start -2.2987 2.999994)
			(end -2.500122 2.999994)
			(stroke
				(width 0.1524)
				(type default)
			)
			(layer "F.SilkS")
		)
		(fp_line
			(start 2.31394 -2.999994)
			(end 2.500122 -2.999994)
			(stroke
				(width 0.1524)
				(type default)
			)
			(layer "F.SilkS")
		)
		(fp_line
			(start 2.500122 -2.999994)
			(end 2.500122 -2.44348)
			(stroke
				(width 0.1524)
				(type default)
			)
			(layer "F.SilkS")
		)
		(fp_line
			(start 2.500122 2.339594)
			(end 2.500122 2.999994)
			(stroke
				(width 0.1524)
				(type default)
			)
			(layer "F.SilkS")
		)
		(fp_line
			(start 2.500122 2.999994)
			(end 2.2987 2.999994)
			(stroke
				(width 0.1524)
				(type default)
			)
			(layer "F.SilkS")
		)
		(fp_poly
			(pts
				(xy -3.438652 -2.681478) (xy -2.968752 -3.151378) (xy -2.734056 -2.446782)
			)
			(stroke
				(width 0)
				(type default)
			)
			(fill yes)
			(layer "F.SilkS")
		)
		(fp_line
			(start -2.500122 -2.999994)
			(end 2.500122 -2.999994)
			(stroke
				(width 0.1)
				(type default)
			)
			(layer "F.Fab")
		)
		(fp_line
			(start -2.500122 2.999994)
			(end -2.500122 -2.999994)
			(stroke
				(width 0.1)
				(type default)
			)
			(layer "F.Fab")
		)
		(fp_line
			(start 2.500122 -2.999994)
			(end 2.500122 2.999994)
			(stroke
				(width 0.1)
				(type default)
			)
			(layer "F.Fab")
		)
		(fp_line
			(start 2.500122 2.999994)
			(end -2.500122 2.999994)
			(stroke
				(width 0.1)
				(type default)
			)
			(layer "F.Fab")
		)
		(fp_poly
			(pts
				(xy -4.218432 -2.783078) (xy -4.218432 -1.767078) (xy -3.202432 -2.275078)
			)
			(stroke
				(width 0)
				(type default)
			)
			(fill yes)
			(layer "F.Fab")
		)
		(pad "1" smd rect
			(at -2.400046 -2.275078 90)
			(size 0.2286 0.6096)
			(layers "F.Cu" "F.Mask" "F.Paste")
			(net "PVDDCR_CPU1_P0_VOS4")
		)
		(pad "2" smd rect
			(at -2.400046 -1.82499 90)
			(size 0.2286 0.6096)
			(layers "F.Cu" "F.Mask" "F.Paste")
			(net "GND")
		)
		(pad "3" smd rect
			(at -2.400046 -1.374902 90)
			(size 0.2286 0.6096)
			(layers "F.Cu" "F.Mask" "F.Paste")
			(net "PVDDCR_CPU1_P0_VCC4")
		)
		(pad "4" smd rect
			(at -2.400046 -0.925068 90)
			(size 0.2286 0.6096)
			(layers "F.Cu" "F.Mask" "F.Paste")
			(net "PVDDCR_CPU1_P0_PVCC")
		)
		(pad "5" smd rect
			(at -2.400046 -0.47498 90)
			(size 0.2286 0.6096)
			(layers "F.Cu" "F.Mask" "F.Paste")
			(net "GND")
		)
		(pad "6" smd rect
			(at -2.400046 -0.024892 90)
			(size 0.2286 0.6096)
			(layers "F.Cu" "F.Mask" "F.Paste")
			(net "NC_PVDDCR_CPU1_P0_GL1_4")
		)
		(pad "7_9-20_24" smd circle
			(at 0 1.150112 90)
			(size 0 0)
			(layers "F.Cu" "F.Mask" "F.Paste")
			(net "GND")
		)
		(pad "10_19" smd rect
			(at 0 2.899918 90)
			(size 0.6096 4.318)
			(layers "F.Cu" "F.Mask" "F.Paste")
			(net "SW_PVDDCR_CPU1_P0_SW4")
		)
		(pad "25_29" smd rect
			(at 1.549908 -1.279906 270)
			(size 2.0574 2.3114)
			(layers "F.Cu" "F.Mask" "F.Paste")
			(net "SW_P12V_AUX_PVDDCR_CPU1_P0_FLT")
		)
		(pad "30" smd rect
			(at 2.05994 -2.899918)
			(size 0.2286 0.6096)
			(layers "F.Cu" "F.Mask" "F.Paste")
			(net "SW_P12V_AUX_PVDDCR_CPU1_P0_FLT")
		)
		(pad "31" smd rect
			(at 1.610106 -2.899918)
			(size 0.2286 0.6096)
			(layers "F.Cu" "F.Mask" "F.Paste")
			(net "NC_PVDDCR_CPU1_P0_DNC4")
		)
		(pad "32" smd rect
			(at 1.160018 -2.899918)
			(size 0.2286 0.6096)
			(layers "F.Cu" "F.Mask" "F.Paste")
			(net "SW_PVDDCR_CPU1_P0_BOOTR4")
		)
		(pad "33" smd rect
			(at 0.70993 -2.899918)
			(size 0.2286 0.6096)
			(layers "F.Cu" "F.Mask" "F.Paste")
			(net "SW_PVDDCR_CPU1_P0_BOOT4")
		)
		(pad "34" smd rect
			(at 0.260096 -2.899918)
			(size 0.2286 0.6096)
			(layers "F.Cu" "F.Mask" "F.Paste")
			(net "PVDDCR_CPU1_P0_PWM4")
		)
		(pad "35" smd rect
			(at -0.189992 -2.899918)
			(size 0.2286 0.6096)
			(layers "F.Cu" "F.Mask" "F.Paste")
			(net "PVDDCR_CPU1_P0_VCC4")
		)
		(pad "36" smd rect
			(at -0.64008 -2.899918)
			(size 0.2286 0.6096)
			(layers "F.Cu" "F.Mask" "F.Paste")
			(net "PVDDCR_CPU1_P0_TEMP0")
		)
		(pad "37" smd rect
			(at -1.089914 -2.899918)
			(size 0.2286 0.6096)
			(layers "F.Cu" "F.Mask" "F.Paste")
			(net "PVDDCR_CPU1_P0_LSET4")
		)
		(pad "38" smd rect
			(at -1.540002 -2.899918)
			(size 0.2286 0.6096)
			(layers "F.Cu" "F.Mask" "F.Paste")
			(net "PVDDCR_CPU1_P0_IMON4")
		)
		(pad "39" smd rect
			(at -1.99009 -2.899918)
			(size 0.2286 0.6096)
			(layers "F.Cu" "F.Mask" "F.Paste")
			(net "PVDDCR_CPU1_P0_VCCS")
		)
		(pad "40" smd rect
			(at -0.87503 -1.27508)
			(size 1.7526 1.9558)
			(layers "F.Cu" "F.Mask" "F.Paste")
			(net "GND")
		)
		(pad "41" smd rect
			(at -1.525016 0.249936 270)
			(size 0.3048 0.4572)
			(layers "F.Cu" "F.Mask" "F.Paste")
			(net "NC_PVDDCR_CPU1_P0_GL2_4")
		)
		(zone
			(layer "F.Cu")
			(hatch none 0.5)
			(connect_pads
				(clearance 0)
			)
			(min_thickness 0.25)
			(keepout
				(tracks not_allowed)
				(vias allowed)
				(pads allowed)
				(copperpour not_allowed)
				(footprints allowed)
			)
			(placement
				(enabled no)
				(sheetname "")
			)
			(fill
				(thermal_gap 0.5)
				(thermal_bridge_width 0.5)
				(island_removal_mode 0)
			)
			(polygon
				(pts
					(xy 306.195984 -344.147394) (xy 306.195984 -344.465656) (xy 311.196228 -344.465656) (xy 311.196228 -344.136472)
					(xy 310.905906 -344.136472) (xy 310.905906 -344.172032) (xy 306.486306 -344.172032) (xy 306.486306 -344.147394)
				)
			)
		)
		(zone
			(layer "F.Cu")
			(hatch none 0.5)
			(connect_pads
				(clearance 0)
			)
			(min_thickness 0.25)
			(keepout
				(tracks not_allowed)
				(vias allowed)
				(pads allowed)
				(copperpour not_allowed)
				(footprints allowed)
			)
			(placement
				(enabled no)
				(sheetname "")
			)
			(fill
				(thermal_gap 0.5)
				(thermal_bridge_width 0.5)
				(island_removal_mode 0)
			)
			(polygon
				(pts
					(xy 308.748176 -346.96273) (xy 308.748176 -349.02013) (xy 306.893976 -349.02013) (xy 306.893976 -348.779084)
					(xy 306.65166 -348.779084) (xy 306.65166 -349.260668) (xy 310.491886 -349.260668) (xy 310.491886 -349.075756)
					(xy 309.039514 -349.075756) (xy 309.039514 -346.916756) (xy 311.196228 -346.916756) (xy 311.196228 -346.667074)
					(xy 309.043832 -346.667074)
				)
			)
		)
	)
)
